(kicad_pcb
	(version 20241229)
	(generator "pcbnew")
	(generator_version "9.0")
	(general
		(thickness 1.294)
		(legacy_teardrops no)
	)
	(paper "A3")
	(title_block
		(title "Kintex 410T devboard")
		(date "2024-04-03")
		(rev "1.1.2")
		(comment 9 "footprints 470-474 of 975")
	)
	(layers
		(0 "F.Cu" mixed)
		(4 "In1.Cu" power)
		(6 "In2.Cu" power)
		(8 "In3.Cu" mixed)
		(10 "In4.Cu" power)
		(12 "In5.Cu" mixed)
		(14 "In6.Cu" power)
		(16 "In7.Cu" mixed)
		(18 "In8.Cu" power)
		(2 "B.Cu" mixed)
		(9 "F.Adhes" user "F.Adhesive")
		(11 "B.Adhes" user "B.Adhesive")
		(13 "F.Paste" user)
		(15 "B.Paste" user)
		(5 "F.SilkS" user "F.Silkscreen")
		(7 "B.SilkS" user "B.Silkscreen")
		(1 "F.Mask" user)
		(3 "B.Mask" user)
		(17 "Dwgs.User" user "User.Drawings")
		(19 "Cmts.User" user "User.Comments")
		(21 "Eco1.User" user "User.Eco1")
		(23 "Eco2.User" user "User.Eco2")
		(25 "Edge.Cuts" user)
		(27 "Margin" user)
		(31 "F.CrtYd" user "F.Courtyard")
		(29 "B.CrtYd" user "B.Courtyard")
		(35 "F.Fab" user)
		(33 "B.Fab" user)
	)
	(footprint "antmicro-footprints:R_0402_1005Metric"
		(layer "F.Cu")
		(at 236.35 146.45 180)
		(descr "Resistor SMD 0402")
		(tags "resistor SMD 0402")
		(property "Reference" "R182"
			(at 1.05 -4.45 180)
			(layer "F.SilkS")
			(effects
				(font
					(size 0.7 0.7)
					(thickness 0.15)
				)
				(justify left bottom)
			)
		)
		(property "Value" "R_33R_0402"
			(at 0 1.4 180)
			(layer "F.Fab")
			(effects
				(font
					(size 0.7 0.7)
					(thickness 0.15)
				)
				(justify left bottom)
			)
		)
		(property "Description" "SMD Chip Resistor, 33 ohm, ± 1%, 62.5 mW, 0402 [1005 Metric], Thick Film, General Purpose"
			(at 0 0 180)
			(layer "F.Fab")
			(hide yes)
			(effects
				(font
					(size 1.27 1.27)
					(thickness 0.15)
				)
			)
		)
		(property "Author" "Antmicro"
			(at 472.7 292.9 0)
			(layer "F.Fab")
			(hide yes)
			(effects
				(font
					(size 1 1)
					(thickness 0.15)
				)
			)
		)
		(property "License" "Apache-2.0"
			(at 472.7 292.9 0)
			(layer "F.Fab")
			(hide yes)
			(effects
				(font
					(size 1 1)
					(thickness 0.15)
				)
			)
		)
		(property "MPN" "CR0402-FX-33R0GLF"
			(at 472.7 292.9 0)
			(layer "F.Fab")
			(hide yes)
			(effects
				(font
					(size 1 1)
					(thickness 0.15)
				)
			)
		)
		(property "Manufacturer" "Bourns"
			(at 472.7 292.9 0)
			(layer "F.Fab")
			(hide yes)
			(effects
				(font
					(size 1 1)
					(thickness 0.15)
				)
			)
		)
		(property "Tolerance" "1%"
			(at 472.7 292.9 0)
			(layer "F.Fab")
			(hide yes)
			(effects
				(font
					(size 1 1)
					(thickness 0.15)
				)
			)
		)
		(property "Val" "33R"
			(at 472.7 292.9 0)
			(layer "F.Fab")
			(hide yes)
			(effects
				(font
					(size 1 1)
					(thickness 0.15)
				)
			)
		)
		(sheetname "USB PHY")
		(sheetfile "usb-phy.kicad_sch")
		(attr smd)
		(fp_rect
			(start -0.925 -0.47)
			(end 0.925 0.47)
			(stroke
				(width 0.05)
				(type default)
			)
			(fill no)
			(layer "F.CrtYd")
		)
		(fp_rect
			(start -0.5 -0.25)
			(end 0.5 0.25)
			(stroke
				(width 0.15)
				(type solid)
			)
			(fill no)
			(layer "F.Fab")
		)
		(pad "1" smd roundrect
			(at -0.48 0 180)
			(size 0.59 0.64)
			(layers "F.Cu" "F.Mask" "F.Paste")
			(roundrect_rratio 0.25)
			(net 374 "Net-(U23-B1Y)")
			(pintype "passive")
		)
		(pad "2" smd roundrect
			(at 0.48 0 180)
			(size 0.59 0.64)
			(layers "F.Cu" "F.Mask" "F.Paste")
			(roundrect_rratio 0.25)
			(net 1296 "/USB_SPI.SCK")
			(pintype "passive")
		)
	)
	(footprint "antmicro-footprints:WDFN-8-1EP_6x5mm_P1.27mm_EP3.4x4mm"
		(layer "F.Cu")
		(at 230.475 113.15)
		(property "Reference" "U14"
			(at -3.7 -3.2 0)
			(layer "F.SilkS")
			(effects
				(font
					(size 0.7 0.7)
					(thickness 0.15)
				)
				(justify left bottom)
			)
		)
		(property "Value" "MT25QL256ABA1EW7-0SIT"
			(at -10.1 4 0)
			(layer "F.Fab")
			(effects
				(font
					(size 0.7 0.7)
					(thickness 0.15)
				)
				(justify left bottom)
			)
		)
		(property "Description" "Flash Memory, Serial NOR, 256 Mbit, 32M x 8bit, SPI, MLP, 8 Pins"
			(at 0 0 0)
			(layer "F.Fab")
			(hide yes)
			(effects
				(font
					(size 1.27 1.27)
					(thickness 0.15)
				)
			)
		)
		(property "Author" "Antmicro"
			(at 0 0 0)
			(layer "F.Fab")
			(hide yes)
			(effects
				(font
					(size 1 1)
					(thickness 0.15)
				)
			)
		)
		(property "DNP" "DNP"
			(at 0 0 0)
			(layer "F.Fab")
			(hide yes)
			(effects
				(font
					(size 1 1)
					(thickness 0.15)
				)
			)
		)
		(property "License" "Apache-2.0"
			(at 0 0 0)
			(layer "F.Fab")
			(hide yes)
			(effects
				(font
					(size 1 1)
					(thickness 0.15)
				)
			)
		)
		(property "MPN" "MT25QL256ABA1EW7-0SIT"
			(at 0 0 0)
			(layer "F.Fab")
			(hide yes)
			(effects
				(font
					(size 1 1)
					(thickness 0.15)
				)
			)
		)
		(property "Manufacturer" "Micron Technology"
			(at 0 0 0)
			(layer "F.Fab")
			(hide yes)
			(effects
				(font
					(size 1 1)
					(thickness 0.15)
				)
			)
		)
		(property "dnp" ""
			(at 0 0 0)
			(layer "F.Fab")
			(hide yes)
			(effects
				(font
					(size 1 1)
					(thickness 0.15)
				)
			)
		)
		(property "exclude_from_bom" ""
			(at 0 0 0)
			(layer "F.Fab")
			(hide yes)
			(effects
				(font
					(size 1 1)
					(thickness 0.15)
				)
			)
		)
		(sheetname "SPI Flash + SD Card")
		(sheetfile "spi-flash.kicad_sch")
		(attr smd exclude_from_bom)
		(fp_line
			(start -3.801 2.6)
			(end 3.7 2.6)
			(stroke
				(width 0.15)
				(type solid)
			)
			(layer "F.SilkS")
		)
		(fp_line
			(start -2.301 -2.601)
			(end 3.7 -2.601)
			(stroke
				(width 0.15)
				(type solid)
			)
			(layer "F.SilkS")
		)
		(fp_circle
			(center -3.3 -2.8)
			(end -3.25 -2.8)
			(stroke
				(width 0.15)
				(type solid)
			)
			(fill yes)
			(layer "F.SilkS")
		)
		(fp_rect
			(start -3.5 -3)
			(end 3.499 2.999)
			(stroke
				(width 0.05)
				(type solid)
			)
			(fill no)
			(layer "F.CrtYd")
		)
		(fp_line
			(start -3 -1.5)
			(end -3 2.499)
			(stroke
				(width 0.15)
				(type solid)
			)
			(layer "F.Fab")
		)
		(fp_line
			(start -3 2.499)
			(end 2.999 2.499)
			(stroke
				(width 0.15)
				(type solid)
			)
			(layer "F.Fab")
		)
		(fp_line
			(start -2 -2.5)
			(end -3 -1.5)
			(stroke
				(width 0.15)
				(type solid)
			)
			(layer "F.Fab")
		)
		(fp_line
			(start 2.999 -2.5)
			(end -2 -2.5)
			(stroke
				(width 0.15)
				(type solid)
			)
			(layer "F.Fab")
		)
		(fp_line
			(start 2.999 2.499)
			(end 2.999 -2.5)
			(stroke
				(width 0.15)
				(type solid)
			)
			(layer "F.Fab")
		)
		(pad "" smd roundrect
			(at -0.802 -1)
			(size 1.37 1.61)
			(layers "F.Paste")
			(roundrect_rratio 0.182482)
		)
		(pad "" smd roundrect
			(at -0.802 0.998)
			(size 1.37 1.61)
			(layers "F.Paste")
			(roundrect_rratio 0.182482)
		)
		(pad "" smd roundrect
			(at 0.8 -1)
			(size 1.37 1.61)
			(layers "F.Paste")
			(roundrect_rratio 0.182482)
		)
		(pad "" smd roundrect
			(at 0.8 0.998)
			(size 1.37 1.61)
			(layers "F.Paste")
			(roundrect_rratio 0.182482)
		)
		(pad "1" smd rect
			(at -3 -1.905 90)
			(size 0.5 1.5)
			(layers "F.Cu" "F.Mask" "F.Paste")
			(net 906 "/SPI Flash + SD Card/USR_FLASH_1_~{CS}")
			(pinfunction "~{CS}")
			(pintype "passive")
		)
		(pad "2" smd roundrect
			(at -3 -0.635 90)
			(size 0.5 1.5)
			(layers "F.Cu" "F.Mask" "F.Paste")
			(roundrect_rratio 0.25)
			(net 909 "/SPI Flash + SD Card/USR_FLASH_1_DQ1")
			(pinfunction "DQ1")
			(pintype "passive")
		)
		(pad "3" smd roundrect
			(at -3 0.633 90)
			(size 0.5 1.5)
			(layers "F.Cu" "F.Mask" "F.Paste")
			(roundrect_rratio 0.25)
			(net 910 "/SPI Flash + SD Card/USR_FLASH_1_DQ2")
			(pinfunction "DQ2/~{W}")
			(pintype "passive")
		)
		(pad "4" smd roundrect
			(at -3 1.904 90)
			(size 0.5 1.5)
			(layers "F.Cu" "F.Mask" "F.Paste")
			(roundrect_rratio 0.25)
			(net 1 "GND")
			(pinfunction "GND")
			(pintype "passive")
		)
		(pad "5" smd roundrect
			(at 2.999 1.904 90)
			(size 0.5 1.5)
			(layers "F.Cu" "F.Mask" "F.Paste")
			(roundrect_rratio 0.25)
			(net 908 "/SPI Flash + SD Card/USR_FLASH_1_DQ0")
			(pinfunction "DQ0")
			(pintype "passive")
		)
		(pad "6" smd roundrect
			(at 2.999 0.633 90)
			(size 0.5 1.5)
			(layers "F.Cu" "F.Mask" "F.Paste")
			(roundrect_rratio 0.25)
			(net 907 "/SPI Flash + SD Card/USR_FLASH_1_CLK")
			(pinfunction "CLK")
			(pintype "passive")
		)
		(pad "7" smd roundrect
			(at 2.999 -0.635 90)
			(size 0.5 1.5)
			(layers "F.Cu" "F.Mask" "F.Paste")
			(roundrect_rratio 0.25)
			(net 911 "/SPI Flash + SD Card/USR_FLASH_1_DQ3")
			(pinfunction "DQ3/~{HOLD}")
			(pintype "passive")
		)
		(pad "8" smd roundrect
			(at 2.999 -1.905 90)
			(size 0.5 1.5)
			(layers "F.Cu" "F.Mask" "F.Paste")
			(roundrect_rratio 0.25)
			(net 3 "VCC_USR_B")
			(pinfunction "VCC")
			(pintype "passive")
		)
		(pad "9" smd rect
			(at 0 0)
			(size 3.4 4)
			(layers "F.Cu" "F.Mask")
			(net 1 "GND")
			(pinfunction "EP")
			(pintype "passive")
			(solder_paste_margin -0.1)
		)
	)
	(footprint "antmicro-footprints:R_0402_1005Metric"
		(layer "F.Cu")
		(at 199.901 109.249 180)
		(descr "Resistor SMD 0402")
		(tags "resistor SMD 0402")
		(property "Reference" "R154"
			(at -0.899 -0.351 180)
			(layer "F.SilkS")
			(effects
				(font
					(size 0.7 0.7)
					(thickness 0.15)
				)
				(justify left bottom)
			)
		)
		(property "Value" "R_33R_0402"
			(at 0 1.4 180)
			(layer "F.Fab")
			(effects
				(font
					(size 0.7 0.7)
					(thickness 0.15)
				)
				(justify left bottom)
			)
		)
		(property "Description" "SMD Chip Resistor, 33 ohm, ± 1%, 62.5 mW, 0402 [1005 Metric], Thick Film, General Purpose"
			(at 0 0 180)
			(layer "F.Fab")
			(hide yes)
			(effects
				(font
					(size 1.27 1.27)
					(thickness 0.15)
				)
			)
		)
		(property "Author" "Antmicro"
			(at 399.802 218.498 0)
			(layer "F.Fab")
			(hide yes)
			(effects
				(font
					(size 1 1)
					(thickness 0.15)
				)
			)
		)
		(property "License" "Apache-2.0"
			(at 399.802 218.498 0)
			(layer "F.Fab")
			(hide yes)
			(effects
				(font
					(size 1 1)
					(thickness 0.15)
				)
			)
		)
		(property "MPN" "CR0402-FX-33R0GLF"
			(at 399.802 218.498 0)
			(layer "F.Fab")
			(hide yes)
			(effects
				(font
					(size 1 1)
					(thickness 0.15)
				)
			)
		)
		(property "Manufacturer" "Bourns"
			(at 399.802 218.498 0)
			(layer "F.Fab")
			(hide yes)
			(effects
				(font
					(size 1 1)
					(thickness 0.15)
				)
			)
		)
		(property "Tolerance" "1%"
			(at 399.802 218.498 0)
			(layer "F.Fab")
			(hide yes)
			(effects
				(font
					(size 1 1)
					(thickness 0.15)
				)
			)
		)
		(property "Val" "33R"
			(at 399.802 218.498 0)
			(layer "F.Fab")
			(hide yes)
			(effects
				(font
					(size 1 1)
					(thickness 0.15)
				)
			)
		)
		(sheetname "USB PHY")
		(sheetfile "usb-phy.kicad_sch")
		(attr smd)
		(fp_rect
			(start -0.925 -0.47)
			(end 0.925 0.47)
			(stroke
				(width 0.05)
				(type default)
			)
			(fill no)
			(layer "F.CrtYd")
		)
		(fp_rect
			(start -0.5 -0.25)
			(end 0.5 0.25)
			(stroke
				(width 0.15)
				(type solid)
			)
			(fill no)
			(layer "F.Fab")
		)
		(pad "1" smd roundrect
			(at -0.48 0 180)
			(size 0.59 0.64)
			(layers "F.Cu" "F.Mask" "F.Paste")
			(roundrect_rratio 0.25)
			(net 835 "/USB PHY/USB_HOST_CONN_D-")
			(pintype "passive")
		)
		(pad "2" smd roundrect
			(at 0.48 0 180)
			(size 0.59 0.64)
			(layers "F.Cu" "F.Mask" "F.Paste")
			(roundrect_rratio 0.25)
			(net 916 "/USB PHY/USB_HOST_D-")
			(pintype "passive")
		)
	)
	(footprint "antmicro-footprints:C_0402_1005Metric"
		(layer "F.Cu")
		(at 207.4125 91.1115 180)
		(descr "Capacitor SMD 0402")
		(tags "capacitor SMD 0402")
		(property "Reference" "C262"
			(at 1.8125 4.5615 180)
			(layer "F.SilkS")
			(effects
				(font
					(size 0.7 0.7)
					(thickness 0.15)
				)
				(justify left bottom)
			)
		)
		(property "Value" "C_100n_0402"
			(at 0 1.169 180)
			(layer "F.Fab")
			(effects
				(font
					(size 0.7 0.7)
					(thickness 0.15)
				)
				(justify left bottom)
			)
		)
		(property "Description" "SMD Multilayer Ceramic Capacitor, 0.1 µF, 50 V, 0402 [1005 Metric], ± 10%, X5R, GRM Series"
			(at 0 0 180)
			(layer "F.Fab")
			(hide yes)
			(effects
				(font
					(size 1.27 1.27)
					(thickness 0.15)
				)
			)
		)
		(property "Author" "Antmicro"
			(at 414.825 182.223 0)
			(layer "F.Fab")
			(hide yes)
			(effects
				(font
					(size 1 1)
					(thickness 0.15)
				)
			)
		)
		(property "Dielectric" "X5R"
			(at 414.825 182.223 0)
			(layer "F.Fab")
			(hide yes)
			(effects
				(font
					(size 1 1)
					(thickness 0.15)
				)
			)
		)
		(property "License" "Apache-2.0"
			(at 414.825 182.223 0)
			(layer "F.Fab")
			(hide yes)
			(effects
				(font
					(size 1 1)
					(thickness 0.15)
				)
			)
		)
		(property "MPN" "GRM155R61H104KE14D"
			(at 414.825 182.223 0)
			(layer "F.Fab")
			(hide yes)
			(effects
				(font
					(size 1 1)
					(thickness 0.15)
				)
			)
		)
		(property "Manufacturer" "Murata"
			(at 414.825 182.223 0)
			(layer "F.Fab")
			(hide yes)
			(effects
				(font
					(size 1 1)
					(thickness 0.15)
				)
			)
		)
		(property "Val" "100n"
			(at 414.825 182.223 0)
			(layer "F.Fab")
			(hide yes)
			(effects
				(font
					(size 1 1)
					(thickness 0.15)
				)
			)
		)
		(property "Voltage" "50V"
			(at 414.825 182.223 0)
			(layer "F.Fab")
			(hide yes)
			(effects
				(font
					(size 1 1)
					(thickness 0.15)
				)
			)
		)
		(sheetname "HDMI + Ethernet")
		(sheetfile "hdmi-ethernet.kicad_sch")
		(attr smd)
		(fp_rect
			(start -0.925 -0.47)
			(end 0.925 0.47)
			(stroke
				(width 0.05)
				(type default)
			)
			(fill no)
			(layer "F.CrtYd")
		)
		(fp_line
			(start 0.504 0.248)
			(end -0.494 0.248)
			(stroke
				(width 0.15)
				(type solid)
			)
			(layer "F.Fab")
		)
		(fp_line
			(start 0.504 -0.25)
			(end 0.504 0.248)
			(stroke
				(width 0.15)
				(type solid)
			)
			(layer "F.Fab")
		)
		(fp_line
			(start -0.494 0.248)
			(end -0.494 -0.25)
			(stroke
				(width 0.15)
				(type solid)
			)
			(layer "F.Fab")
		)
		(fp_line
			(start -0.494 -0.25)
			(end 0.504 -0.25)
			(stroke
				(width 0.15)
				(type solid)
			)
			(layer "F.Fab")
		)
		(pad "1" smd roundrect
			(at -0.48 0 180)
			(size 0.59 0.64)
			(layers "F.Cu" "F.Mask" "F.Paste")
			(roundrect_rratio 0.25)
			(net 1 "GND")
			(pintype "passive")
		)
		(pad "2" smd roundrect
			(at 0.48 0 180)
			(size 0.59 0.64)
			(layers "F.Cu" "F.Mask" "F.Paste")
			(roundrect_rratio 0.25)
			(net 717 "/HDMI + Ethernet/GBE_AVDDH")
			(pintype "passive")
		)
	)
	(footprint "antmicro-footprints:R_0402_1005Metric"
		(layer "F.Cu")
		(at 162.5275 175.75)
		(descr "Resistor SMD 0402")
		(tags "resistor SMD 0402")
		(property "Reference" "R309"
			(at -0.9275 1.25 0)
			(layer "F.SilkS")
			(effects
				(font
					(size 0.7 0.7)
					(thickness 0.15)
				)
				(justify left bottom)
			)
		)
		(property "Value" "R_0R_0402"
			(at 0 1.4 0)
			(layer "F.Fab")
			(effects
				(font
					(size 0.7 0.7)
					(thickness 0.15)
				)
				(justify left bottom)
			)
		)
		(property "Description" "SMD Chip Resistor, Jumper, 0 ohm, 100 mW, 0402 [1005 Metric], Thick Film, General Purpose"
			(at 0 0 0)
			(layer "F.Fab")
			(hide yes)
			(effects
				(font
					(size 1.27 1.27)
					(thickness 0.15)
				)
			)
		)
		(property "Author" "Antmicro"
			(at 0 0 0)
			(layer "F.Fab")
			(hide yes)
			(effects
				(font
					(size 1 1)
					(thickness 0.15)
				)
			)
		)
		(property "Current" "1A"
			(at 0 0 0)
			(layer "F.Fab")
			(hide yes)
			(effects
				(font
					(size 1 1)
					(thickness 0.15)
				)
			)
		)
		(property "License" "Apache-2.0"
			(at 0 0 0)
			(layer "F.Fab")
			(hide yes)
			(effects
				(font
					(size 1 1)
					(thickness 0.15)
				)
			)
		)
		(property "MPN" "ERJ2GE0R00X"
			(at 0 0 0)
			(layer "F.Fab")
			(hide yes)
			(effects
				(font
					(size 1 1)
					(thickness 0.15)
				)
			)
		)
		(property "Manufacturer" "Panasonic"
			(at 0 0 0)
			(layer "F.Fab")
			(hide yes)
			(effects
				(font
					(size 1 1)
					(thickness 0.15)
				)
			)
		)
		(property "Tolerance" ""
			(at 0 0 0)
			(layer "F.Fab")
			(hide yes)
			(effects
				(font
					(size 1 1)
					(thickness 0.15)
				)
			)
		)
		(property "Val" "0R"
			(at 0 0 0)
			(layer "F.Fab")
			(hide yes)
			(effects
				(font
					(size 1 1)
					(thickness 0.15)
				)
			)
		)
		(sheetname "DC-DC Converters")
		(sheetfile "dc-dc.kicad_sch")
		(attr smd)
		(fp_rect
			(start -0.925 -0.47)
			(end 0.925 0.47)
			(stroke
				(width 0.05)
				(type default)
			)
			(fill no)
			(layer "F.CrtYd")
		)
		(fp_rect
			(start -0.5 -0.25)
			(end 0.5 0.25)
			(stroke
				(width 0.15)
				(type solid)
			)
			(fill no)
			(layer "F.Fab")
		)
		(pad "1" smd roundrect
			(at -0.48 0)
			(size 0.59 0.64)
			(layers "F.Cu" "F.Mask" "F.Paste")
			(roundrect_rratio 0.25)
			(net 962 "/DC-DC Converters/FB3")
			(pintype "passive")
		)
		(pad "2" smd roundrect
			(at 0.48 0)
			(size 0.59 0.64)
			(layers "F.Cu" "F.Mask" "F.Paste")
			(roundrect_rratio 0.25)
			(net 737 "/DC-DC Converters/1V2_local")
			(pintype "passive")
		)
	)
)
